# S9S_MB_2U (Grand Teton) — schematic netlist excerpt (pin names and nets, part order shuffled) for the footprints in the layout excerpt that follows; sources: Cadence DE-HDL packaged netlist, KiCad conversion of 03242023_DA0F0TMBIJ0_F0T_Motherboard_J_brd_V01_OCP.brd

C859  Q_CAP_DIFFBUS  DIFF BUS_0.22UF 6.3V 20% X6S  pkg C0201  page 174 : \1\ = P5E_CPU0_PE1_TX_C_DP<5> ; \2\ = P5E_CPU0_PE1_TX_DP<5>

(kicad_pcb
	(version 20260206)
	(generator "pcbnew")
	(generator_version "10.0")
	(general
		(thickness 1.6)
		(legacy_teardrops no)
	)
	(paper "A4")
	(title_block
		(title "03242023_DA0F0TMBIJ0_F0T_Motherboard_J_brd_V01_OCP.brd")
		(comment 1 "Grand Teton / footprints 590-590 of 6105")
	)
	(layers
		(0 "F.Cu" signal "TOP")
		(4 "In1.Cu" signal "GND")
		(6 "In2.Cu" signal "IN1")
		(8 "In3.Cu" signal "GND1")
		(10 "In4.Cu" signal "IN2")
		(12 "In5.Cu" signal "GND2")
		(14 "In6.Cu" signal "IN3")
		(16 "In7.Cu" signal "GND3")
		(18 "In8.Cu" signal "VCC")
		(20 "In9.Cu" signal "VCC1")
		(22 "In10.Cu" signal "GND4")
		(24 "In11.Cu" signal "IN4")
		(26 "In12.Cu" signal "GND5")
		(28 "In13.Cu" signal "IN5")
		(30 "In14.Cu" signal "GND6")
		(32 "In15.Cu" signal "IN6")
		(34 "In16.Cu" signal "GND7")
		(2 "B.Cu" signal "BOTTOM")
		(9 "F.Adhes" user "F.Adhesive")
		(11 "B.Adhes" user "B.Adhesive")
		(13 "F.Paste" user "Package Geometry/Pastemask Top")
		(15 "B.Paste" user "Package Geometry/Pastemask Bottom")
		(5 "F.SilkS" user "Ref Des/Silkscreen Top")
		(7 "B.SilkS" user "Ref Des/Silkscreen Bottom")
		(1 "F.Mask" user "Board Geometry/Soldermask Top")
		(3 "B.Mask" user "Board Geometry/Soldermask Bottom")
		(17 "Dwgs.User" user "User.Drawings")
		(19 "Cmts.User" user "User.Comments")
		(21 "Eco1.User" user "User.Eco1")
		(23 "Eco2.User" user "User.Eco2")
		(25 "Edge.Cuts" user "Board Geometry/Outline")
		(27 "Margin" user)
		(31 "F.CrtYd" user "Package Geometry/Place Bound Top")
		(29 "B.CrtYd" user "Package Geometry/Place Bound Bottom")
		(35 "F.Fab" user "Ref Des/Assembly Top")
		(33 "B.Fab" user "Ref Des/Assembly Bottom")
	)
	(footprint ""
		(layer "F.Cu")
		(at 418.2618 -16.088614 90)
		(property "Reference" "C859"
			(at 0 0 90)
			(layer "F.SilkS")
			(hide yes)
			(effects
				(font
					(size 1.27 1.27)
				)
			)
		)
		(property "Value" ""
			(at 0 0 90)
			(layer "F.Fab")
			(effects
				(font
					(size 1.27 1.27)
				)
			)
		)
		(duplicate_pad_numbers_are_jumpers no)
		(fp_line
			(start 0.299974 -0.150114)
			(end 0.299974 0.150114)
			(stroke
				(width 0.1)
				(type default)
			)
			(layer "F.Fab")
		)
		(fp_line
			(start -0.299974 -0.150114)
			(end 0.299974 -0.150114)
			(stroke
				(width 0.1)
				(type default)
			)
			(layer "F.Fab")
		)
		(fp_line
			(start 0.299974 0.150114)
			(end -0.299974 0.150114)
			(stroke
				(width 0.1)
				(type default)
			)
			(layer "F.Fab")
		)
		(fp_line
			(start -0.299974 0.150114)
			(end -0.299974 -0.150114)
			(stroke
				(width 0.1)
				(type default)
			)
			(layer "F.Fab")
		)
		(pad "1" smd rect
			(at -0.2667 0 90)
			(size 0.3048 0.381)
			(layers "F.Cu" "F.Mask" "F.Paste")
			(net "P5E_CPU0_PE1_TX_C_DP<5>")
		)
		(pad "2" smd rect
			(at 0.2667 0 90)
			(size 0.3048 0.381)
			(layers "F.Cu" "F.Mask" "F.Paste")
			(net "P5E_CPU0_PE1_TX_DP<5>")
		)
	)
)
